#ISCELL
  mstr_misc dns *
  *
#ISCELL
  pure_quanta quanta_title_block_c *
  *
#ISCELL
  logical_power universal_power *
  page26_i10
#CELL
  pure_quanta q_res *
  page26_i11
#CELL
  pure_quanta q_res *
  page26_i12
#ISCELL
  logical_power universal_gnd *
  page26_i13
#CELL
  pure_quanta q_res *
  page26_i14
#CELL
  pure_quanta m24128bwdw6tp *
  page26_i15
#ISCELL
  logical_power universal_gnd *
  page26_i16
#CELL
  pure_quanta q_cap *
  page26_i17
#ISCELL
  logical_power universal_power *
  page26_i18
#ISCELL
  logical_power universal_gnd *
  page26_i31
#CELL
  pure_quanta q_res *
  page26_i32
#CELL
  pure_quanta q_res *
  page26_i33
#ISCELL
  standard offpage *
  page26_i35
#ISCELL
  standard offpage *
  page26_i36
#CELL
  pure_quanta q_res *
  page26_i37
#ISCELL
  logical_power universal_gnd *
  page26_i38
#CELL
  pure_quanta q_res *
  page26_i39
#CELL
  pure_quanta q_res *
  page26_i40
#CELL
  pure_quanta q_res *
  page26_i41
#ISCELL
  logical_power universal_gnd *
  page26_i52
#ISCELL
  logical_power universal_power *
  page26_i53
#CELL
  pure_quanta q_cap *
  page26_i54
#ISCELL
  logical_power universal_gnd *
  page26_i55
#CELL
  pure_quanta q_res *
  page26_i56
#CELL
  pure_quanta q_res *
  page26_i57
#ISCELL
  logical_power universal_power *
  page26_i58
#ISCELL
  standard offpage *
  page26_i59
#CELL
  pure_quanta q_res *
  page26_i6
#ISCELL
  standard offpage *
  page26_i60
#CELL
  pure_quanta q_res *
  page26_i65
#CELL
  pure_quanta q_res *
  page26_i66
#CELL
  pure_quanta q_res *
  page26_i67
#ISCELL
  standard offpage *
  page26_i68
#CELL
  pure_quanta q_res *
  page26_i69
#ISCELL
  logical_power universal_gnd *
  page26_i7
#CELL
  pure_quanta conn8_tsw10407fd *
  page26_i71
#CELL
  pure_quanta q_res *
  page26_i8
#CELL
  pure_quanta q_res *
  page26_i9
